(kicad_pcb
	(version 20260206)
	(generator "pcbnew")
	(generator_version "10.0")
	(general
		(thickness 1.6)
		(legacy_teardrops no)
	)
	(paper "A4")
	(title_block
		(title "04192023_DAF0TMB3IC0_F0TG_MB_C_brd_V02_OCP.brd")
		(comment 1 "Grand Teton / footprints 906-912 of 8354")
	)
	(layers
		(0 "F.Cu" signal "TOP")
		(4 "In1.Cu" signal "GND")
		(6 "In2.Cu" signal "IN1")
		(8 "In3.Cu" signal "GND1")
		(10 "In4.Cu" signal "IN2")
		(12 "In5.Cu" signal "GND2")
		(14 "In6.Cu" signal "IN3")
		(16 "In7.Cu" signal "GND3")
		(18 "In8.Cu" signal "VCC")
		(20 "In9.Cu" signal "VCC1")
		(22 "In10.Cu" signal "GND4")
		(24 "In11.Cu" signal "IN4")
		(26 "In12.Cu" signal "GND5")
		(28 "In13.Cu" signal "IN5")
		(30 "In14.Cu" signal "GND6")
		(32 "In15.Cu" signal "IN6")
		(34 "In16.Cu" signal "GND7")
		(2 "B.Cu" signal "BOTTOM")
		(9 "F.Adhes" user "F.Adhesive")
		(11 "B.Adhes" user "B.Adhesive")
		(13 "F.Paste" user "Package Geometry/Pastemask Top")
		(15 "B.Paste" user "Package Geometry/Pastemask Bottom")
		(5 "F.SilkS" user "Ref Des/Silkscreen Top")
		(7 "B.SilkS" user "Ref Des/Silkscreen Bottom")
		(1 "F.Mask" user "Board Geometry/Soldermask Top")
		(3 "B.Mask" user "Board Geometry/Soldermask Bottom")
		(17 "Dwgs.User" user "User.Drawings")
		(19 "Cmts.User" user "User.Comments")
		(21 "Eco1.User" user "User.Eco1")
		(23 "Eco2.User" user "User.Eco2")
		(25 "Edge.Cuts" user "Board Geometry/Outline")
		(27 "Margin" user)
		(31 "F.CrtYd" user "Package Geometry/Place Bound Top")
		(29 "B.CrtYd" user "Package Geometry/Place Bound Bottom")
		(35 "F.Fab" user "Ref Des/Assembly Top")
		(33 "B.Fab" user "Ref Des/Assembly Bottom")
	)
	(footprint ""
		(layer "F.Cu")
		(at 71.16826 -339.651848 90)
		(property "Reference" "PR267"
			(at 0 0 90)
			(layer "F.SilkS")
			(hide yes)
			(effects
				(font
					(size 1.27 1.27)
				)
			)
		)
		(property "Value" ""
			(at 0 0 90)
			(layer "F.Fab")
			(effects
				(font
					(size 1.27 1.27)
				)
			)
		)
		(duplicate_pad_numbers_are_jumpers no)
		(fp_line
			(start 0.7874 -0.4064)
			(end 0.7874 0.4064)
			(stroke
				(width 0.1524)
				(type default)
			)
			(layer "F.SilkS")
		)
		(fp_line
			(start -0.7874 -0.4064)
			(end 0.7874 -0.4064)
			(stroke
				(width 0.1524)
				(type default)
			)
			(layer "F.SilkS")
		)
		(fp_line
			(start 0.7874 0.4064)
			(end -0.7874 0.4064)
			(stroke
				(width 0.1524)
				(type default)
			)
			(layer "F.SilkS")
		)
		(fp_line
			(start -0.7874 0.4064)
			(end -0.7874 -0.4064)
			(stroke
				(width 0.1524)
				(type default)
			)
			(layer "F.SilkS")
		)
		(fp_line
			(start -0.12065 -0.305054)
			(end -0.12065 -0.2794)
			(stroke
				(width 0.1)
				(type default)
			)
			(layer "F.Fab")
		)
		(fp_line
			(start -0.67945 -0.305054)
			(end -0.12065 -0.305054)
			(stroke
				(width 0.1)
				(type default)
			)
			(layer "F.Fab")
		)
		(fp_line
			(start 0.67945 -0.3048)
			(end 0.67945 0.3048)
			(stroke
				(width 0.1)
				(type default)
			)
			(layer "F.Fab")
		)
		(fp_line
			(start 0.12065 -0.3048)
			(end 0.67945 -0.3048)
			(stroke
				(width 0.1)
				(type default)
			)
			(layer "F.Fab")
		)
		(fp_line
			(start 0.12065 -0.2794)
			(end 0.12065 -0.3048)
			(stroke
				(width 0.1)
				(type default)
			)
			(layer "F.Fab")
		)
		(fp_line
			(start -0.12065 -0.2794)
			(end 0.12065 -0.2794)
			(stroke
				(width 0.1)
				(type default)
			)
			(layer "F.Fab")
		)
		(fp_line
			(start 0.120396 0.2794)
			(end -0.12065 0.2794)
			(stroke
				(width 0.1)
				(type default)
			)
			(layer "F.Fab")
		)
		(fp_line
			(start -0.12065 0.2794)
			(end -0.12065 0.3048)
			(stroke
				(width 0.1)
				(type default)
			)
			(layer "F.Fab")
		)
		(fp_line
			(start 0.67945 0.3048)
			(end 0.120396 0.3048)
			(stroke
				(width 0.1)
				(type default)
			)
			(layer "F.Fab")
		)
		(fp_line
			(start 0.120396 0.3048)
			(end 0.120396 0.2794)
			(stroke
				(width 0.1)
				(type default)
			)
			(layer "F.Fab")
		)
		(fp_line
			(start -0.12065 0.3048)
			(end -0.67945 0.3048)
			(stroke
				(width 0.1)
				(type default)
			)
			(layer "F.Fab")
		)
		(fp_line
			(start -0.67945 0.3048)
			(end -0.67945 -0.305054)
			(stroke
				(width 0.1)
				(type default)
			)
			(layer "F.Fab")
		)
		(pad "1" smd circle
			(at -0.40005 0 90)
			(size 0 0)
			(layers "F.Cu" "F.Mask" "F.Paste")
			(net "SW_PVDDCR_CPU1_P1_BOOT3")
		)
		(pad "2" smd circle
			(at 0.40005 0 90)
			(size 0 0)
			(layers "F.Cu" "F.Mask" "F.Paste")
			(net "SW_PVDDCR_CPU1_P1_BOOT3_R")
		)
	)
	(footprint ""
		(layer "F.Cu")
		(at 455.524616 -403.12467 180)
		(property "Reference" "PC6578_2"
			(at 0 0 180)
			(layer "F.SilkS")
			(hide yes)
			(effects
				(font
					(size 1.27 1.27)
				)
			)
		)
		(property "Value" ""
			(at 0 0 180)
			(layer "F.Fab")
			(effects
				(font
					(size 1.27 1.27)
				)
			)
		)
		(duplicate_pad_numbers_are_jumpers no)
		(fp_line
			(start 0.7874 0.4064)
			(end -0.7874 0.4064)
			(stroke
				(width 0.1524)
				(type default)
			)
			(layer "F.SilkS")
		)
		(fp_line
			(start 0.7874 -0.4064)
			(end 0.7874 0.4064)
			(stroke
				(width 0.1524)
				(type default)
			)
			(layer "F.SilkS")
		)
		(fp_line
			(start -0.7874 0.4064)
			(end -0.7874 -0.4064)
			(stroke
				(width 0.1524)
				(type default)
			)
			(layer "F.SilkS")
		)
		(fp_line
			(start -0.7874 -0.4064)
			(end 0.7874 -0.4064)
			(stroke
				(width 0.1524)
				(type default)
			)
			(layer "F.SilkS")
		)
		(fp_line
			(start 0.67945 0.3048)
			(end 0.120396 0.3048)
			(stroke
				(width 0.1)
				(type default)
			)
			(layer "F.Fab")
		)
		(fp_line
			(start 0.67945 -0.3048)
			(end 0.67945 0.3048)
			(stroke
				(width 0.1)
				(type default)
			)
			(layer "F.Fab")
		)
		(fp_line
			(start 0.12065 -0.2794)
			(end 0.12065 -0.3048)
			(stroke
				(width 0.1)
				(type default)
			)
			(layer "F.Fab")
		)
		(fp_line
			(start 0.12065 -0.3048)
			(end 0.67945 -0.3048)
			(stroke
				(width 0.1)
				(type default)
			)
			(layer "F.Fab")
		)
		(fp_line
			(start 0.120396 0.3048)
			(end 0.120396 0.2794)
			(stroke
				(width 0.1)
				(type default)
			)
			(layer "F.Fab")
		)
		(fp_line
			(start 0.120396 0.2794)
			(end -0.12065 0.2794)
			(stroke
				(width 0.1)
				(type default)
			)
			(layer "F.Fab")
		)
		(fp_line
			(start -0.12065 0.3048)
			(end -0.67945 0.3048)
			(stroke
				(width 0.1)
				(type default)
			)
			(layer "F.Fab")
		)
		(fp_line
			(start -0.12065 0.2794)
			(end -0.12065 0.3048)
			(stroke
				(width 0.1)
				(type default)
			)
			(layer "F.Fab")
		)
		(fp_line
			(start -0.12065 -0.2794)
			(end 0.12065 -0.2794)
			(stroke
				(width 0.1)
				(type default)
			)
			(layer "F.Fab")
		)
		(fp_line
			(start -0.12065 -0.305054)
			(end -0.12065 -0.2794)
			(stroke
				(width 0.1)
				(type default)
			)
			(layer "F.Fab")
		)
		(fp_line
			(start -0.67945 0.3048)
			(end -0.67945 -0.305054)
			(stroke
				(width 0.1)
				(type default)
			)
			(layer "F.Fab")
		)
		(fp_line
			(start -0.67945 -0.305054)
			(end -0.12065 -0.305054)
			(stroke
				(width 0.1)
				(type default)
			)
			(layer "F.Fab")
		)
		(pad "1" smd circle
			(at -0.40005 0 180)
			(size 0 0)
			(layers "F.Cu" "F.Mask" "F.Paste")
			(net "SW_P12V_AUX_P0V9_RETIMER_CPU0_FLT")
		)
		(pad "2" smd circle
			(at 0.40005 0 180)
			(size 0 0)
			(layers "F.Cu" "F.Mask" "F.Paste")
			(net "GND")
		)
	)
	(footprint ""
		(layer "F.Cu")
		(at 164.719 -106.299 180)
		(property "Reference" "R9024"
			(at 0 0 180)
			(layer "F.SilkS")
			(hide yes)
			(effects
				(font
					(size 1.27 1.27)
				)
			)
		)
		(property "Value" ""
			(at 0 0 180)
			(layer "F.Fab")
			(effects
				(font
					(size 1.27 1.27)
				)
			)
		)
		(duplicate_pad_numbers_are_jumpers no)
		(fp_line
			(start 0.7874 0.4064)
			(end -0.7874 0.4064)
			(stroke
				(width 0.1524)
				(type default)
			)
			(layer "F.SilkS")
		)
		(fp_line
			(start 0.7874 -0.4064)
			(end 0.7874 0.4064)
			(stroke
				(width 0.1524)
				(type default)
			)
			(layer "F.SilkS")
		)
		(fp_line
			(start -0.7874 0.4064)
			(end -0.7874 -0.4064)
			(stroke
				(width 0.1524)
				(type default)
			)
			(layer "F.SilkS")
		)
		(fp_line
			(start -0.7874 -0.4064)
			(end 0.7874 -0.4064)
			(stroke
				(width 0.1524)
				(type default)
			)
			(layer "F.SilkS")
		)
		(fp_line
			(start 0.67945 0.3048)
			(end 0.120396 0.3048)
			(stroke
				(width 0.1)
				(type default)
			)
			(layer "F.Fab")
		)
		(fp_line
			(start 0.67945 -0.3048)
			(end 0.67945 0.3048)
			(stroke
				(width 0.1)
				(type default)
			)
			(layer "F.Fab")
		)
		(fp_line
			(start 0.12065 -0.2794)
			(end 0.12065 -0.3048)
			(stroke
				(width 0.1)
				(type default)
			)
			(layer "F.Fab")
		)
		(fp_line
			(start 0.12065 -0.3048)
			(end 0.67945 -0.3048)
			(stroke
				(width 0.1)
				(type default)
			)
			(layer "F.Fab")
		)
		(fp_line
			(start 0.120396 0.3048)
			(end 0.120396 0.2794)
			(stroke
				(width 0.1)
				(type default)
			)
			(layer "F.Fab")
		)
		(fp_line
			(start 0.120396 0.2794)
			(end -0.12065 0.2794)
			(stroke
				(width 0.1)
				(type default)
			)
			(layer "F.Fab")
		)
		(fp_line
			(start -0.12065 0.3048)
			(end -0.67945 0.3048)
			(stroke
				(width 0.1)
				(type default)
			)
			(layer "F.Fab")
		)
		(fp_line
			(start -0.12065 0.2794)
			(end -0.12065 0.3048)
			(stroke
				(width 0.1)
				(type default)
			)
			(layer "F.Fab")
		)
		(fp_line
			(start -0.12065 -0.2794)
			(end 0.12065 -0.2794)
			(stroke
				(width 0.1)
				(type default)
			)
			(layer "F.Fab")
		)
		(fp_line
			(start -0.12065 -0.305054)
			(end -0.12065 -0.2794)
			(stroke
				(width 0.1)
				(type default)
			)
			(layer "F.Fab")
		)
		(fp_line
			(start -0.67945 0.3048)
			(end -0.67945 -0.305054)
			(stroke
				(width 0.1)
				(type default)
			)
			(layer "F.Fab")
		)
		(fp_line
			(start -0.67945 -0.305054)
			(end -0.12065 -0.305054)
			(stroke
				(width 0.1)
				(type default)
			)
			(layer "F.Fab")
		)
		(pad "1" smd circle
			(at -0.40005 0 180)
			(size 0 0)
			(layers "F.Cu" "F.Mask" "F.Paste")
			(net "P3V3_AUX")
		)
		(pad "2" smd circle
			(at 0.40005 0 180)
			(size 0 0)
			(layers "F.Cu" "F.Mask" "F.Paste")
			(net "IRQ_HSC_FAULT_N")
		)
	)
	(footprint ""
		(layer "F.Cu")
		(at 317.452248 -344.814906)
		(property "Reference" "H37"
			(at 0.040132 -4.391914 0)
			(unlocked yes)
			(layer "F.SilkS")
			(effects
				(font
					(size 0.7874 0.5842)
					(thickness 0.1524)
				)
				(justify left)
			)
		)
		(property "Value" ""
			(at 0 0 0)
			(layer "F.Fab")
			(effects
				(font
					(size 1.27 1.27)
				)
			)
		)
		(duplicate_pad_numbers_are_jumpers no)
		(pad "1" thru_hole circle
			(at 0 0)
			(size 6.1976 6.1976)
			(drill 3.7338)
			(layers "*.Cu" "*.Mask")
			(remove_unused_layers no)
			(net "GND")
			(clearance -0.9779)
			(padstack
				(mode front_inner_back)
				(layer "Inner"
					(shape circle)
					(size 5.5372 5.5372)
					(clearance -0.6477)
				)
				(layer "B.Cu"
					(shape circle)
					(size 6.1976 6.1976)
					(clearance -0.9779)
				)
			)
		)
	)
	(footprint ""
		(layer "F.Cu")
		(at 347.575124 -344.35161)
		(property "Reference" "PC114_6"
			(at 0 0 0)
			(layer "F.SilkS")
			(hide yes)
			(effects
				(font
					(size 1.27 1.27)
				)
			)
		)
		(property "Value" ""
			(at 0 0 0)
			(layer "F.Fab")
			(effects
				(font
					(size 1.27 1.27)
				)
			)
		)
		(duplicate_pad_numbers_are_jumpers no)
		(fp_line
			(start -0.7874 -0.4064)
			(end 0.7874 -0.4064)
			(stroke
				(width 0.1524)
				(type default)
			)
			(layer "F.SilkS")
		)
		(fp_line
			(start -0.7874 0.4064)
			(end -0.7874 -0.4064)
			(stroke
				(width 0.1524)
				(type default)
			)
			(layer "F.SilkS")
		)
		(fp_line
			(start 0.7874 -0.4064)
			(end 0.7874 0.4064)
			(stroke
				(width 0.1524)
				(type default)
			)
			(layer "F.SilkS")
		)
		(fp_line
			(start 0.7874 0.4064)
			(end -0.7874 0.4064)
			(stroke
				(width 0.1524)
				(type default)
			)
			(layer "F.SilkS")
		)
		(fp_line
			(start -0.67945 -0.305054)
			(end -0.12065 -0.305054)
			(stroke
				(width 0.1)
				(type default)
			)
			(layer "F.Fab")
		)
		(fp_line
			(start -0.67945 0.3048)
			(end -0.67945 -0.305054)
			(stroke
				(width 0.1)
				(type default)
			)
			(layer "F.Fab")
		)
		(fp_line
			(start -0.12065 -0.305054)
			(end -0.12065 -0.2794)
			(stroke
				(width 0.1)
				(type default)
			)
			(layer "F.Fab")
		)
		(fp_line
			(start -0.12065 -0.2794)
			(end 0.12065 -0.2794)
			(stroke
				(width 0.1)
				(type default)
			)
			(layer "F.Fab")
		)
		(fp_line
			(start -0.12065 0.2794)
			(end -0.12065 0.3048)
			(stroke
				(width 0.1)
				(type default)
			)
			(layer "F.Fab")
		)
		(fp_line
			(start -0.12065 0.3048)
			(end -0.67945 0.3048)
			(stroke
				(width 0.1)
				(type default)
			)
			(layer "F.Fab")
		)
		(fp_line
			(start 0.120396 0.2794)
			(end -0.12065 0.2794)
			(stroke
				(width 0.1)
				(type default)
			)
			(layer "F.Fab")
		)
		(fp_line
			(start 0.120396 0.3048)
			(end 0.120396 0.2794)
			(stroke
				(width 0.1)
				(type default)
			)
			(layer "F.Fab")
		)
		(fp_line
			(start 0.12065 -0.3048)
			(end 0.67945 -0.3048)
			(stroke
				(width 0.1)
				(type default)
			)
			(layer "F.Fab")
		)
		(fp_line
			(start 0.12065 -0.2794)
			(end 0.12065 -0.3048)
			(stroke
				(width 0.1)
				(type default)
			)
			(layer "F.Fab")
		)
		(fp_line
			(start 0.67945 -0.3048)
			(end 0.67945 0.3048)
			(stroke
				(width 0.1)
				(type default)
			)
			(layer "F.Fab")
		)
		(fp_line
			(start 0.67945 0.3048)
			(end 0.120396 0.3048)
			(stroke
				(width 0.1)
				(type default)
			)
			(layer "F.Fab")
		)
		(pad "1" smd circle
			(at -0.40005 0)
			(size 0 0)
			(layers "F.Cu" "F.Mask" "F.Paste")
			(net "SW_P12V_AUX_PVDDCR_CPU1_P0_FLT")
		)
		(pad "2" smd circle
			(at 0.40005 0)
			(size 0 0)
			(layers "F.Cu" "F.Mask" "F.Paste")
			(net "GND")
		)
	)
	(footprint ""
		(layer "F.Cu")
		(at 113.613946 -52.86248 -90)
		(property "Reference" "R6300"
			(at 0 0 270)
			(layer "F.SilkS")
			(hide yes)
			(effects
				(font
					(size 1.27 1.27)
				)
			)
		)
		(property "Value" ""
			(at 0 0 270)
			(layer "F.Fab")
			(effects
				(font
					(size 1.27 1.27)
				)
			)
		)
		(duplicate_pad_numbers_are_jumpers no)
		(fp_line
			(start -0.7874 0.4064)
			(end -0.7874 -0.4064)
			(stroke
				(width 0.1524)
				(type default)
			)
			(layer "F.SilkS")
		)
		(fp_line
			(start 0.7874 0.4064)
			(end -0.7874 0.4064)
			(stroke
				(width 0.1524)
				(type default)
			)
			(layer "F.SilkS")
		)
		(fp_line
			(start -0.7874 -0.4064)
			(end 0.7874 -0.4064)
			(stroke
				(width 0.1524)
				(type default)
			)
			(layer "F.SilkS")
		)
		(fp_line
			(start 0.7874 -0.4064)
			(end 0.7874 0.4064)
			(stroke
				(width 0.1524)
				(type default)
			)
			(layer "F.SilkS")
		)
		(fp_line
			(start -0.67945 0.3048)
			(end -0.67945 -0.305054)
			(stroke
				(width 0.1)
				(type default)
			)
			(layer "F.Fab")
		)
		(fp_line
			(start -0.12065 0.3048)
			(end -0.67945 0.3048)
			(stroke
				(width 0.1)
				(type default)
			)
			(layer "F.Fab")
		)
		(fp_line
			(start 0.120396 0.3048)
			(end 0.120396 0.2794)
			(stroke
				(width 0.1)
				(type default)
			)
			(layer "F.Fab")
		)
		(fp_line
			(start 0.67945 0.3048)
			(end 0.120396 0.3048)
			(stroke
				(width 0.1)
				(type default)
			)
			(layer "F.Fab")
		)
		(fp_line
			(start -0.12065 0.2794)
			(end -0.12065 0.3048)
			(stroke
				(width 0.1)
				(type default)
			)
			(layer "F.Fab")
		)
		(fp_line
			(start 0.120396 0.2794)
			(end -0.12065 0.2794)
			(stroke
				(width 0.1)
				(type default)
			)
			(layer "F.Fab")
		)
		(fp_line
			(start -0.12065 -0.2794)
			(end 0.12065 -0.2794)
			(stroke
				(width 0.1)
				(type default)
			)
			(layer "F.Fab")
		)
		(fp_line
			(start 0.12065 -0.2794)
			(end 0.12065 -0.3048)
			(stroke
				(width 0.1)
				(type default)
			)
			(layer "F.Fab")
		)
		(fp_line
			(start 0.12065 -0.3048)
			(end 0.67945 -0.3048)
			(stroke
				(width 0.1)
				(type default)
			)
			(layer "F.Fab")
		)
		(fp_line
			(start 0.67945 -0.3048)
			(end 0.67945 0.3048)
			(stroke
				(width 0.1)
				(type default)
			)
			(layer "F.Fab")
		)
		(fp_line
			(start -0.67945 -0.305054)
			(end -0.12065 -0.305054)
			(stroke
				(width 0.1)
				(type default)
			)
			(layer "F.Fab")
		)
		(fp_line
			(start -0.12065 -0.305054)
			(end -0.12065 -0.2794)
			(stroke
				(width 0.1)
				(type default)
			)
			(layer "F.Fab")
		)
		(pad "1" smd circle
			(at -0.40005 0 270)
			(size 0 0)
			(layers "F.Cu" "F.Mask" "F.Paste")
			(net "USB_HUB2_MRP_CFG_BC_EN")
		)
		(pad "2" smd circle
			(at 0.40005 0 270)
			(size 0 0)
			(layers "F.Cu" "F.Mask" "F.Paste")
			(net "USB_HUB2_TI_OVERCUR3_MRP_CFG_BC_EN")
		)
	)
	(footprint ""
		(layer "F.Cu")
		(at 261.62 -141.986 -90)
		(property "Reference" "R8008"
			(at 0 0 270)
			(layer "F.SilkS")
			(hide yes)
			(effects
				(font
					(size 1.27 1.27)
				)
			)
		)
		(property "Value" ""
			(at 0 0 270)
			(layer "F.Fab")
			(effects
				(font
					(size 1.27 1.27)
				)
			)
		)
		(duplicate_pad_numbers_are_jumpers no)
		(fp_line
			(start -0.7874 0.4064)
			(end -0.7874 -0.4064)
			(stroke
				(width 0.1524)
				(type default)
			)
			(layer "F.SilkS")
		)
		(fp_line
			(start 0.7874 0.4064)
			(end -0.7874 0.4064)
			(stroke
				(width 0.1524)
				(type default)
			)
			(layer "F.SilkS")
		)
		(fp_line
			(start -0.7874 -0.4064)
			(end 0.7874 -0.4064)
			(stroke
				(width 0.1524)
				(type default)
			)
			(layer "F.SilkS")
		)
		(fp_line
			(start 0.7874 -0.4064)
			(end 0.7874 0.4064)
			(stroke
				(width 0.1524)
				(type default)
			)
			(layer "F.SilkS")
		)
		(fp_line
			(start -0.67945 0.3048)
			(end -0.67945 -0.305054)
			(stroke
				(width 0.1)
				(type default)
			)
			(layer "F.Fab")
		)
		(fp_line
			(start -0.12065 0.3048)
			(end -0.67945 0.3048)
			(stroke
				(width 0.1)
				(type default)
			)
			(layer "F.Fab")
		)
		(fp_line
			(start 0.120396 0.3048)
			(end 0.120396 0.2794)
			(stroke
				(width 0.1)
				(type default)
			)
			(layer "F.Fab")
		)
		(fp_line
			(start 0.67945 0.3048)
			(end 0.120396 0.3048)
			(stroke
				(width 0.1)
				(type default)
			)
			(layer "F.Fab")
		)
		(fp_line
			(start -0.12065 0.2794)
			(end -0.12065 0.3048)
			(stroke
				(width 0.1)
				(type default)
			)
			(layer "F.Fab")
		)
		(fp_line
			(start 0.120396 0.2794)
			(end -0.12065 0.2794)
			(stroke
				(width 0.1)
				(type default)
			)
			(layer "F.Fab")
		)
		(fp_line
			(start -0.12065 -0.2794)
			(end 0.12065 -0.2794)
			(stroke
				(width 0.1)
				(type default)
			)
			(layer "F.Fab")
		)
		(fp_line
			(start 0.12065 -0.2794)
			(end 0.12065 -0.3048)
			(stroke
				(width 0.1)
				(type default)
			)
			(layer "F.Fab")
		)
		(fp_line
			(start 0.12065 -0.3048)
			(end 0.67945 -0.3048)
			(stroke
				(width 0.1)
				(type default)
			)
			(layer "F.Fab")
		)
		(fp_line
			(start 0.67945 -0.3048)
			(end 0.67945 0.3048)
			(stroke
				(width 0.1)
				(type default)
			)
			(layer "F.Fab")
		)
		(fp_line
			(start -0.67945 -0.305054)
			(end -0.12065 -0.305054)
			(stroke
				(width 0.1)
				(type default)
			)
			(layer "F.Fab")
		)
		(fp_line
			(start -0.12065 -0.305054)
			(end -0.12065 -0.2794)
			(stroke
				(width 0.1)
				(type default)
			)
			(layer "F.Fab")
		)
		(pad "1" smd circle
			(at -0.40005 0 270)
			(size 0 0)
			(layers "F.Cu" "F.Mask" "F.Paste")
			(net "SPI_CPU0_D1")
		)
		(pad "2" smd circle
			(at 0.40005 0 270)
			(size 0 0)
			(layers "F.Cu" "F.Mask" "F.Paste")
			(net "SPI_CPU0_R1_D1")
		)
	)
)
